#ISCELL
  pure_quanta quanta_title_block_c *
  *
#CELL
  pure_quanta socket4677_azif0045p001c01cs *
  page67_i1
#ISCELL
  logical_power vcc_core *
  page67_i2
#CELL
  pure_quanta socket4677_azif0045p001c01cs *
  page67_i3
#ISCELL
  logical_power vcc_core *
  page67_i4
#ISCELL
  logical_power vcc_core *
  page67_i5
#ISCELL
  logical_power vcc_core *
  page67_i6
